# T6G (Grand Teton) — schematic netlist excerpt (pin names and nets, part order shuffled) for the footprints in the layout excerpt that follows; sources: Cadence DE-HDL packaged netlist, KiCad conversion of 04192023_DAF0TMB3IC0_F0TG_MB_C_brd_V02_OCP.brd

PC286  Q_CAP  2.2UF 10V 10% X6S  pkg C0402  page 212 : A = PVDDCR_CPU0_P1_VCC3 ; B = GND
PC73  Q_CAP  1UF 6.3V 10% X7R  pkg 0402  page 200 : A = PVDD18_S5_P0 ; B = GND

(kicad_pcb
	(version 20260206)
	(generator "pcbnew")
	(generator_version "10.0")
	(general
		(thickness 1.6)
		(legacy_teardrops no)
	)
	(paper "A4")
	(title_block
		(title "04192023_DAF0TMB3IC0_F0TG_MB_C_brd_V02_OCP.brd")
		(comment 1 "Grand Teton / footprints 3312-3313 of 8354")
	)
	(layers
		(0 "F.Cu" signal "TOP")
		(4 "In1.Cu" signal "GND")
		(6 "In2.Cu" signal "IN1")
		(8 "In3.Cu" signal "GND1")
		(10 "In4.Cu" signal "IN2")
		(12 "In5.Cu" signal "GND2")
		(14 "In6.Cu" signal "IN3")
		(16 "In7.Cu" signal "GND3")
		(18 "In8.Cu" signal "VCC")
		(20 "In9.Cu" signal "VCC1")
		(22 "In10.Cu" signal "GND4")
		(24 "In11.Cu" signal "IN4")
		(26 "In12.Cu" signal "GND5")
		(28 "In13.Cu" signal "IN5")
		(30 "In14.Cu" signal "GND6")
		(32 "In15.Cu" signal "IN6")
		(34 "In16.Cu" signal "GND7")
		(2 "B.Cu" signal "BOTTOM")
		(9 "F.Adhes" user "F.Adhesive")
		(11 "B.Adhes" user "B.Adhesive")
		(13 "F.Paste" user "Package Geometry/Pastemask Top")
		(15 "B.Paste" user "Package Geometry/Pastemask Bottom")
		(5 "F.SilkS" user "Ref Des/Silkscreen Top")
		(7 "B.SilkS" user "Ref Des/Silkscreen Bottom")
		(1 "F.Mask" user "Board Geometry/Soldermask Top")
		(3 "B.Mask" user "Board Geometry/Soldermask Bottom")
		(17 "Dwgs.User" user "User.Drawings")
		(19 "Cmts.User" user "User.Comments")
		(21 "Eco1.User" user "User.Eco1")
		(23 "Eco2.User" user "User.Eco2")
		(25 "Edge.Cuts" user "Board Geometry/Outline")
		(27 "Margin" user)
		(31 "F.CrtYd" user "Package Geometry/Place Bound Top")
		(29 "B.CrtYd" user "Package Geometry/Place Bound Bottom")
		(35 "F.Fab" user "Ref Des/Assembly Top")
		(33 "B.Fab" user "Ref Des/Assembly Bottom")
	)
	(footprint ""
		(layer "F.Cu")
		(at 304.419 -360.426 180)
		(property "Reference" "PC73"
			(at 0 0 180)
			(layer "F.SilkS")
			(hide yes)
			(effects
				(font
					(size 1.27 1.27)
				)
			)
		)
		(property "Value" ""
			(at 0 0 180)
			(layer "F.Fab")
			(effects
				(font
					(size 1.27 1.27)
				)
			)
		)
		(duplicate_pad_numbers_are_jumpers no)
		(fp_line
			(start 0.7874 0.4064)
			(end -0.7874 0.4064)
			(stroke
				(width 0.1524)
				(type default)
			)
			(layer "F.SilkS")
		)
		(fp_line
			(start 0.7874 -0.4064)
			(end 0.7874 0.4064)
			(stroke
				(width 0.1524)
				(type default)
			)
			(layer "F.SilkS")
		)
		(fp_line
			(start -0.7874 0.4064)
			(end -0.7874 -0.4064)
			(stroke
				(width 0.1524)
				(type default)
			)
			(layer "F.SilkS")
		)
		(fp_line
			(start -0.7874 -0.4064)
			(end 0.7874 -0.4064)
			(stroke
				(width 0.1524)
				(type default)
			)
			(layer "F.SilkS")
		)
		(fp_line
			(start 0.67945 0.3048)
			(end 0.120396 0.3048)
			(stroke
				(width 0.1)
				(type default)
			)
			(layer "F.Fab")
		)
		(fp_line
			(start 0.67945 -0.3048)
			(end 0.67945 0.3048)
			(stroke
				(width 0.1)
				(type default)
			)
			(layer "F.Fab")
		)
		(fp_line
			(start 0.12065 -0.2794)
			(end 0.12065 -0.3048)
			(stroke
				(width 0.1)
				(type default)
			)
			(layer "F.Fab")
		)
		(fp_line
			(start 0.12065 -0.3048)
			(end 0.67945 -0.3048)
			(stroke
				(width 0.1)
				(type default)
			)
			(layer "F.Fab")
		)
		(fp_line
			(start 0.120396 0.3048)
			(end 0.120396 0.2794)
			(stroke
				(width 0.1)
				(type default)
			)
			(layer "F.Fab")
		)
		(fp_line
			(start 0.120396 0.2794)
			(end -0.12065 0.2794)
			(stroke
				(width 0.1)
				(type default)
			)
			(layer "F.Fab")
		)
		(fp_line
			(start -0.12065 0.3048)
			(end -0.67945 0.3048)
			(stroke
				(width 0.1)
				(type default)
			)
			(layer "F.Fab")
		)
		(fp_line
			(start -0.12065 0.2794)
			(end -0.12065 0.3048)
			(stroke
				(width 0.1)
				(type default)
			)
			(layer "F.Fab")
		)
		(fp_line
			(start -0.12065 -0.2794)
			(end 0.12065 -0.2794)
			(stroke
				(width 0.1)
				(type default)
			)
			(layer "F.Fab")
		)
		(fp_line
			(start -0.12065 -0.305054)
			(end -0.12065 -0.2794)
			(stroke
				(width 0.1)
				(type default)
			)
			(layer "F.Fab")
		)
		(fp_line
			(start -0.67945 0.3048)
			(end -0.67945 -0.305054)
			(stroke
				(width 0.1)
				(type default)
			)
			(layer "F.Fab")
		)
		(fp_line
			(start -0.67945 -0.305054)
			(end -0.12065 -0.305054)
			(stroke
				(width 0.1)
				(type default)
			)
			(layer "F.Fab")
		)
		(pad "1" smd circle
			(at -0.40005 0 180)
			(size 0 0)
			(layers "F.Cu" "F.Mask" "F.Paste")
			(net "PVDD18_S5_P0")
		)
		(pad "2" smd circle
			(at 0.40005 0 180)
			(size 0 0)
			(layers "F.Cu" "F.Mask" "F.Paste")
			(net "GND")
		)
	)
	(footprint ""
		(layer "F.Cu")
		(at 102.75697 -180.027834 -90)
		(property "Reference" "PC286"
			(at 0 0 270)
			(layer "F.SilkS")
			(hide yes)
			(effects
				(font
					(size 1.27 1.27)
				)
			)
		)
		(property "Value" ""
			(at 0 0 270)
			(layer "F.Fab")
			(effects
				(font
					(size 1.27 1.27)
				)
			)
		)
		(duplicate_pad_numbers_are_jumpers no)
		(fp_line
			(start -0.7874 0.4064)
			(end -0.7874 -0.4064)
			(stroke
				(width 0.1524)
				(type default)
			)
			(layer "F.SilkS")
		)
		(fp_line
			(start -0.235966 0.4064)
			(end -0.7874 0.4064)
			(stroke
				(width 0.1524)
				(type default)
			)
			(layer "F.SilkS")
		)
		(fp_line
			(start 0.7874 0.4064)
			(end 0.373634 0.4064)
			(stroke
				(width 0.1524)
				(type default)
			)
			(layer "F.SilkS")
		)
		(fp_line
			(start -0.7874 -0.4064)
			(end 0.7874 -0.4064)
			(stroke
				(width 0.1524)
				(type default)
			)
			(layer "F.SilkS")
		)
		(fp_line
			(start 0.7874 -0.4064)
			(end 0.7874 0.4064)
			(stroke
				(width 0.1524)
				(type default)
			)
			(layer "F.SilkS")
		)
		(fp_line
			(start -0.67945 0.3048)
			(end -0.67945 -0.305054)
			(stroke
				(width 0.1)
				(type default)
			)
			(layer "F.Fab")
		)
		(fp_line
			(start -0.12065 0.3048)
			(end -0.67945 0.3048)
			(stroke
				(width 0.1)
				(type default)
			)
			(layer "F.Fab")
		)
		(fp_line
			(start 0.120396 0.3048)
			(end 0.120396 0.2794)
			(stroke
				(width 0.1)
				(type default)
			)
			(layer "F.Fab")
		)
		(fp_line
			(start 0.67945 0.3048)
			(end 0.120396 0.3048)
			(stroke
				(width 0.1)
				(type default)
			)
			(layer "F.Fab")
		)
		(fp_line
			(start -0.12065 0.2794)
			(end -0.12065 0.3048)
			(stroke
				(width 0.1)
				(type default)
			)
			(layer "F.Fab")
		)
		(fp_line
			(start 0.120396 0.2794)
			(end -0.12065 0.2794)
			(stroke
				(width 0.1)
				(type default)
			)
			(layer "F.Fab")
		)
		(fp_line
			(start -0.12065 -0.2794)
			(end 0.12065 -0.2794)
			(stroke
				(width 0.1)
				(type default)
			)
			(layer "F.Fab")
		)
		(fp_line
			(start 0.12065 -0.2794)
			(end 0.12065 -0.3048)
			(stroke
				(width 0.1)
				(type default)
			)
			(layer "F.Fab")
		)
		(fp_line
			(start 0.12065 -0.3048)
			(end 0.67945 -0.3048)
			(stroke
				(width 0.1)
				(type default)
			)
			(layer "F.Fab")
		)
		(fp_line
			(start 0.67945 -0.3048)
			(end 0.67945 0.3048)
			(stroke
				(width 0.1)
				(type default)
			)
			(layer "F.Fab")
		)
		(fp_line
			(start -0.67945 -0.305054)
			(end -0.12065 -0.305054)
			(stroke
				(width 0.1)
				(type default)
			)
			(layer "F.Fab")
		)
		(fp_line
			(start -0.12065 -0.305054)
			(end -0.12065 -0.2794)
			(stroke
				(width 0.1)
				(type default)
			)
			(layer "F.Fab")
		)
		(pad "1" smd circle
			(at -0.40005 0 270)
			(size 0 0)
			(layers "F.Cu" "F.Mask" "F.Paste")
			(net "PVDDCR_CPU0_P1_VCC3")
		)
		(pad "2" smd circle
			(at 0.40005 0 270)
			(size 0 0)
			(layers "F.Cu" "F.Mask" "F.Paste")
			(net "GND")
		)
	)
)
